(kicad_pcb
	(version 20260206)
	(generator "pcbnew")
	(generator_version "10.0")
	(general
		(thickness 1.6)
		(legacy_teardrops no)
	)
	(paper "A4")
	(title_block
		(title "04192023_DAF0TMB3IC0_F0TG_MB_C_brd_V02_OCP.brd")
		(comment 1 "Grand Teton / footprints 4723-4727 of 8354")
	)
	(layers
		(0 "F.Cu" signal "TOP")
		(4 "In1.Cu" signal "GND")
		(6 "In2.Cu" signal "IN1")
		(8 "In3.Cu" signal "GND1")
		(10 "In4.Cu" signal "IN2")
		(12 "In5.Cu" signal "GND2")
		(14 "In6.Cu" signal "IN3")
		(16 "In7.Cu" signal "GND3")
		(18 "In8.Cu" signal "VCC")
		(20 "In9.Cu" signal "VCC1")
		(22 "In10.Cu" signal "GND4")
		(24 "In11.Cu" signal "IN4")
		(26 "In12.Cu" signal "GND5")
		(28 "In13.Cu" signal "IN5")
		(30 "In14.Cu" signal "GND6")
		(32 "In15.Cu" signal "IN6")
		(34 "In16.Cu" signal "GND7")
		(2 "B.Cu" signal "BOTTOM")
		(9 "F.Adhes" user "F.Adhesive")
		(11 "B.Adhes" user "B.Adhesive")
		(13 "F.Paste" user "Package Geometry/Pastemask Top")
		(15 "B.Paste" user "Package Geometry/Pastemask Bottom")
		(5 "F.SilkS" user "Ref Des/Silkscreen Top")
		(7 "B.SilkS" user "Ref Des/Silkscreen Bottom")
		(1 "F.Mask" user "Board Geometry/Soldermask Top")
		(3 "B.Mask" user "Board Geometry/Soldermask Bottom")
		(17 "Dwgs.User" user "User.Drawings")
		(19 "Cmts.User" user "User.Comments")
		(21 "Eco1.User" user "User.Eco1")
		(23 "Eco2.User" user "User.Eco2")
		(25 "Edge.Cuts" user "Board Geometry/Outline")
		(27 "Margin" user)
		(31 "F.CrtYd" user "Package Geometry/Place Bound Top")
		(29 "B.CrtYd" user "Package Geometry/Place Bound Bottom")
		(35 "F.Fab" user "Ref Des/Assembly Top")
		(33 "B.Fab" user "Ref Des/Assembly Bottom")
	)
	(footprint ""
		(layer "F.Cu")
		(at 326.701404 -334.988154)
		(property "Reference" "PU2"
			(at 0.450596 -7.631176 0)
			(unlocked yes)
			(layer "F.SilkS")
			(effects
				(font
					(size 0.7874 0.5842)
					(thickness 0.1524)
				)
				(justify left)
			)
		)
		(property "Value" ""
			(at 0 0 0)
			(layer "F.Fab")
			(effects
				(font
					(size 1.27 1.27)
				)
			)
		)
		(duplicate_pad_numbers_are_jumpers no)
		(fp_line
			(start -2.500122 -2.999994)
			(end -2.24409 -2.999994)
			(stroke
				(width 0.1524)
				(type default)
			)
			(layer "F.SilkS")
		)
		(fp_line
			(start -2.500122 -2.529078)
			(end -2.500122 -2.999994)
			(stroke
				(width 0.1524)
				(type default)
			)
			(layer "F.SilkS")
		)
		(fp_line
			(start -2.500122 0.6604)
			(end -2.500122 0.229108)
			(stroke
				(width 0.1524)
				(type default)
			)
			(layer "F.SilkS")
		)
		(fp_line
			(start -2.500122 2.999994)
			(end -2.500122 2.339594)
			(stroke
				(width 0.1524)
				(type default)
			)
			(layer "F.SilkS")
		)
		(fp_line
			(start -2.2987 2.999994)
			(end -2.500122 2.999994)
			(stroke
				(width 0.1524)
				(type default)
			)
			(layer "F.SilkS")
		)
		(fp_line
			(start 2.31394 -2.999994)
			(end 2.500122 -2.999994)
			(stroke
				(width 0.1524)
				(type default)
			)
			(layer "F.SilkS")
		)
		(fp_line
			(start 2.500122 -2.999994)
			(end 2.500122 -2.44348)
			(stroke
				(width 0.1524)
				(type default)
			)
			(layer "F.SilkS")
		)
		(fp_line
			(start 2.500122 2.339594)
			(end 2.500122 2.999994)
			(stroke
				(width 0.1524)
				(type default)
			)
			(layer "F.SilkS")
		)
		(fp_line
			(start 2.500122 2.999994)
			(end 2.2987 2.999994)
			(stroke
				(width 0.1524)
				(type default)
			)
			(layer "F.SilkS")
		)
		(fp_poly
			(pts
				(xy -2.774442 -2.272284) (xy -3.409442 -1.954784) (xy -3.409442 -2.589784)
			)
			(stroke
				(width 0)
				(type default)
			)
			(fill yes)
			(layer "F.SilkS")
		)
		(fp_line
			(start -2.500122 -2.999994)
			(end 2.500122 -2.999994)
			(stroke
				(width 0.1)
				(type default)
			)
			(layer "F.Fab")
		)
		(fp_line
			(start -2.500122 2.999994)
			(end -2.500122 -2.999994)
			(stroke
				(width 0.1)
				(type default)
			)
			(layer "F.Fab")
		)
		(fp_line
			(start 2.500122 -2.999994)
			(end 2.500122 2.999994)
			(stroke
				(width 0.1)
				(type default)
			)
			(layer "F.Fab")
		)
		(fp_line
			(start 2.500122 2.999994)
			(end -2.500122 2.999994)
			(stroke
				(width 0.1)
				(type default)
			)
			(layer "F.Fab")
		)
		(fp_poly
			(pts
				(xy -4.218432 -2.783078) (xy -4.218432 -1.767078) (xy -3.202432 -2.275078)
			)
			(stroke
				(width 0)
				(type default)
			)
			(fill yes)
			(layer "F.Fab")
		)
		(pad "1" smd rect
			(at -2.400046 -2.275078 90)
			(size 0.2286 0.6096)
			(layers "F.Cu" "F.Mask" "F.Paste")
			(net "PVDDCR_CPU1_P0_VOS2")
		)
		(pad "2" smd rect
			(at -2.400046 -1.82499 90)
			(size 0.2286 0.6096)
			(layers "F.Cu" "F.Mask" "F.Paste")
			(net "GND")
		)
		(pad "3" smd rect
			(at -2.400046 -1.374902 90)
			(size 0.2286 0.6096)
			(layers "F.Cu" "F.Mask" "F.Paste")
			(net "PVDDCR_CPU1_P0_VCC2")
		)
		(pad "4" smd rect
			(at -2.400046 -0.925068 90)
			(size 0.2286 0.6096)
			(layers "F.Cu" "F.Mask" "F.Paste")
			(net "PVDDCR_CPU1_P0_PVCC")
		)
		(pad "5" smd rect
			(at -2.400046 -0.47498 90)
			(size 0.2286 0.6096)
			(layers "F.Cu" "F.Mask" "F.Paste")
			(net "GND")
		)
		(pad "6" smd rect
			(at -2.400046 -0.024892 90)
			(size 0.2286 0.6096)
			(layers "F.Cu" "F.Mask" "F.Paste")
			(net "NC_PVDDCR_CPU1_P0_GL1_2")
		)
		(pad "7_9-20_24" smd circle
			(at 0 1.150112 90)
			(size 0 0)
			(layers "F.Cu" "F.Mask" "F.Paste")
			(net "GND")
		)
		(pad "10_19" smd rect
			(at 0 2.899918 90)
			(size 0.6096 4.318)
			(layers "F.Cu" "F.Mask" "F.Paste")
			(net "SW_PVDDCR_CPU1_P0_SW2")
		)
		(pad "25_29" smd rect
			(at 1.549908 -1.279906 270)
			(size 2.0574 2.3114)
			(layers "F.Cu" "F.Mask" "F.Paste")
			(net "SW_P12V_AUX_PVDDCR_CPU1_P0_FLT")
		)
		(pad "30" smd rect
			(at 2.05994 -2.899918)
			(size 0.2286 0.6096)
			(layers "F.Cu" "F.Mask" "F.Paste")
			(net "SW_P12V_AUX_PVDDCR_CPU1_P0_FLT")
		)
		(pad "31" smd rect
			(at 1.610106 -2.899918)
			(size 0.2286 0.6096)
			(layers "F.Cu" "F.Mask" "F.Paste")
			(net "NC_PVDDCR_CPU1_P0_DNC2")
		)
		(pad "32" smd rect
			(at 1.160018 -2.899918)
			(size 0.2286 0.6096)
			(layers "F.Cu" "F.Mask" "F.Paste")
			(net "SW_PVDDCR_CPU1_P0_BOOTR2")
		)
		(pad "33" smd rect
			(at 0.70993 -2.899918)
			(size 0.2286 0.6096)
			(layers "F.Cu" "F.Mask" "F.Paste")
			(net "SW_PVDDCR_CPU1_P0_BOOT2")
		)
		(pad "34" smd rect
			(at 0.260096 -2.899918)
			(size 0.2286 0.6096)
			(layers "F.Cu" "F.Mask" "F.Paste")
			(net "PVDDCR_CPU1_P0_PWM2")
		)
		(pad "35" smd rect
			(at -0.189992 -2.899918)
			(size 0.2286 0.6096)
			(layers "F.Cu" "F.Mask" "F.Paste")
			(net "PVDDCR_CPU1_P0_VCC2")
		)
		(pad "36" smd rect
			(at -0.64008 -2.899918)
			(size 0.2286 0.6096)
			(layers "F.Cu" "F.Mask" "F.Paste")
			(net "PVDDCR_CPU1_P0_TEMP0")
		)
		(pad "37" smd rect
			(at -1.089914 -2.899918)
			(size 0.2286 0.6096)
			(layers "F.Cu" "F.Mask" "F.Paste")
			(net "PVDDCR_CPU1_P0_LSET2")
		)
		(pad "38" smd rect
			(at -1.540002 -2.899918)
			(size 0.2286 0.6096)
			(layers "F.Cu" "F.Mask" "F.Paste")
			(net "PVDDCR_CPU1_P0_IMON2")
		)
		(pad "39" smd rect
			(at -1.99009 -2.899918)
			(size 0.2286 0.6096)
			(layers "F.Cu" "F.Mask" "F.Paste")
			(net "PVDDCR_CPU1_P0_VCCS")
		)
		(pad "40" smd rect
			(at -0.87503 -1.27508)
			(size 1.7526 1.9558)
			(layers "F.Cu" "F.Mask" "F.Paste")
			(net "GND")
		)
		(pad "41" smd rect
			(at -1.525016 0.249936 270)
			(size 0.3048 0.4572)
			(layers "F.Cu" "F.Mask" "F.Paste")
			(net "NC_PVDDCR_CPU1_P0_GL2_2")
		)
		(zone
			(layer "F.Cu")
			(hatch none 0.5)
			(connect_pads
				(clearance 0)
			)
			(min_thickness 0.25)
			(keepout
				(tracks not_allowed)
				(vias allowed)
				(pads allowed)
				(copperpour not_allowed)
				(footprints allowed)
			)
			(placement
				(enabled no)
				(sheetname "")
			)
			(fill
				(thermal_gap 0.5)
				(thermal_bridge_width 0.5)
				(island_removal_mode 0)
			)
			(polygon
				(pts
					(xy 324.201282 -332.418182) (xy 324.201282 -332.73746) (xy 329.201526 -332.73746) (xy 329.201526 -332.406498)
					(xy 328.911204 -332.406498) (xy 328.911204 -332.443836) (xy 324.491604 -332.443836) (xy 324.491604 -332.418182)
				)
			)
		)
		(zone
			(layer "F.Cu")
			(hatch none 0.5)
			(connect_pads
				(clearance 0)
			)
			(min_thickness 0.25)
			(keepout
				(tracks not_allowed)
				(vias allowed)
				(pads allowed)
				(copperpour not_allowed)
				(footprints allowed)
			)
			(placement
				(enabled no)
				(sheetname "")
			)
			(fill
				(thermal_gap 0.5)
				(thermal_bridge_width 0.5)
				(island_removal_mode 0)
			)
			(polygon
				(pts
					(xy 326.753474 -335.234534) (xy 326.753474 -337.291934) (xy 324.899274 -337.291934) (xy 324.899274 -337.050888)
					(xy 324.656958 -337.050888) (xy 324.656958 -337.532472) (xy 328.471022 -337.532472) (xy 328.471022 -337.34756)
					(xy 327.044812 -337.34756) (xy 327.044812 -335.18856) (xy 329.201526 -335.18856) (xy 329.201526 -334.938878)
					(xy 327.04913 -334.938878)
				)
			)
		)
	)
	(footprint ""
		(layer "F.Cu")
		(at 403.682962 -58.2295 180)
		(property "Reference" "R1621"
			(at 0 0 180)
			(layer "F.SilkS")
			(hide yes)
			(effects
				(font
					(size 1.27 1.27)
				)
			)
		)
		(property "Value" ""
			(at 0 0 180)
			(layer "F.Fab")
			(effects
				(font
					(size 1.27 1.27)
				)
			)
		)
		(duplicate_pad_numbers_are_jumpers no)
		(fp_line
			(start 0.7874 0.4064)
			(end -0.7874 0.4064)
			(stroke
				(width 0.1524)
				(type default)
			)
			(layer "F.SilkS")
		)
		(fp_line
			(start 0.7874 -0.4064)
			(end 0.7874 0.4064)
			(stroke
				(width 0.1524)
				(type default)
			)
			(layer "F.SilkS")
		)
		(fp_line
			(start -0.7874 0.4064)
			(end -0.7874 -0.4064)
			(stroke
				(width 0.1524)
				(type default)
			)
			(layer "F.SilkS")
		)
		(fp_line
			(start -0.7874 -0.4064)
			(end 0.7874 -0.4064)
			(stroke
				(width 0.1524)
				(type default)
			)
			(layer "F.SilkS")
		)
		(fp_line
			(start 0.67945 0.3048)
			(end 0.120396 0.3048)
			(stroke
				(width 0.1)
				(type default)
			)
			(layer "F.Fab")
		)
		(fp_line
			(start 0.67945 -0.3048)
			(end 0.67945 0.3048)
			(stroke
				(width 0.1)
				(type default)
			)
			(layer "F.Fab")
		)
		(fp_line
			(start 0.12065 -0.2794)
			(end 0.12065 -0.3048)
			(stroke
				(width 0.1)
				(type default)
			)
			(layer "F.Fab")
		)
		(fp_line
			(start 0.12065 -0.3048)
			(end 0.67945 -0.3048)
			(stroke
				(width 0.1)
				(type default)
			)
			(layer "F.Fab")
		)
		(fp_line
			(start 0.120396 0.3048)
			(end 0.120396 0.2794)
			(stroke
				(width 0.1)
				(type default)
			)
			(layer "F.Fab")
		)
		(fp_line
			(start 0.120396 0.2794)
			(end -0.12065 0.2794)
			(stroke
				(width 0.1)
				(type default)
			)
			(layer "F.Fab")
		)
		(fp_line
			(start -0.12065 0.3048)
			(end -0.67945 0.3048)
			(stroke
				(width 0.1)
				(type default)
			)
			(layer "F.Fab")
		)
		(fp_line
			(start -0.12065 0.2794)
			(end -0.12065 0.3048)
			(stroke
				(width 0.1)
				(type default)
			)
			(layer "F.Fab")
		)
		(fp_line
			(start -0.12065 -0.2794)
			(end 0.12065 -0.2794)
			(stroke
				(width 0.1)
				(type default)
			)
			(layer "F.Fab")
		)
		(fp_line
			(start -0.12065 -0.305054)
			(end -0.12065 -0.2794)
			(stroke
				(width 0.1)
				(type default)
			)
			(layer "F.Fab")
		)
		(fp_line
			(start -0.67945 0.3048)
			(end -0.67945 -0.305054)
			(stroke
				(width 0.1)
				(type default)
			)
			(layer "F.Fab")
		)
		(fp_line
			(start -0.67945 -0.305054)
			(end -0.12065 -0.305054)
			(stroke
				(width 0.1)
				(type default)
			)
			(layer "F.Fab")
		)
		(pad "1" smd circle
			(at -0.40005 0 180)
			(size 0 0)
			(layers "F.Cu" "F.Mask" "F.Paste")
			(net "PVDD18_S5_P0")
		)
		(pad "2" smd circle
			(at 0.40005 0 180)
			(size 0 0)
			(layers "F.Cu" "F.Mask" "F.Paste")
			(net "HDT_HDR_TRST_N_R")
		)
	)
	(footprint ""
		(layer "F.Cu")
		(at 200.939908 -112.609376 180)
		(property "Reference" "R218"
			(at 0 0 180)
			(layer "F.SilkS")
			(hide yes)
			(effects
				(font
					(size 1.27 1.27)
				)
			)
		)
		(property "Value" ""
			(at 0 0 180)
			(layer "F.Fab")
			(effects
				(font
					(size 1.27 1.27)
				)
			)
		)
		(duplicate_pad_numbers_are_jumpers no)
		(fp_line
			(start 0.7874 0.4064)
			(end -0.7874 0.4064)
			(stroke
				(width 0.1524)
				(type default)
			)
			(layer "F.SilkS")
		)
		(fp_line
			(start 0.7874 -0.4064)
			(end 0.7874 0.4064)
			(stroke
				(width 0.1524)
				(type default)
			)
			(layer "F.SilkS")
		)
		(fp_line
			(start -0.7874 0.4064)
			(end -0.7874 -0.4064)
			(stroke
				(width 0.1524)
				(type default)
			)
			(layer "F.SilkS")
		)
		(fp_line
			(start -0.7874 -0.4064)
			(end 0.7874 -0.4064)
			(stroke
				(width 0.1524)
				(type default)
			)
			(layer "F.SilkS")
		)
		(fp_line
			(start 0.67945 0.3048)
			(end 0.120396 0.3048)
			(stroke
				(width 0.1)
				(type default)
			)
			(layer "F.Fab")
		)
		(fp_line
			(start 0.67945 -0.3048)
			(end 0.67945 0.3048)
			(stroke
				(width 0.1)
				(type default)
			)
			(layer "F.Fab")
		)
		(fp_line
			(start 0.12065 -0.2794)
			(end 0.12065 -0.3048)
			(stroke
				(width 0.1)
				(type default)
			)
			(layer "F.Fab")
		)
		(fp_line
			(start 0.12065 -0.3048)
			(end 0.67945 -0.3048)
			(stroke
				(width 0.1)
				(type default)
			)
			(layer "F.Fab")
		)
		(fp_line
			(start 0.120396 0.3048)
			(end 0.120396 0.2794)
			(stroke
				(width 0.1)
				(type default)
			)
			(layer "F.Fab")
		)
		(fp_line
			(start 0.120396 0.2794)
			(end -0.12065 0.2794)
			(stroke
				(width 0.1)
				(type default)
			)
			(layer "F.Fab")
		)
		(fp_line
			(start -0.12065 0.3048)
			(end -0.67945 0.3048)
			(stroke
				(width 0.1)
				(type default)
			)
			(layer "F.Fab")
		)
		(fp_line
			(start -0.12065 0.2794)
			(end -0.12065 0.3048)
			(stroke
				(width 0.1)
				(type default)
			)
			(layer "F.Fab")
		)
		(fp_line
			(start -0.12065 -0.2794)
			(end 0.12065 -0.2794)
			(stroke
				(width 0.1)
				(type default)
			)
			(layer "F.Fab")
		)
		(fp_line
			(start -0.12065 -0.305054)
			(end -0.12065 -0.2794)
			(stroke
				(width 0.1)
				(type default)
			)
			(layer "F.Fab")
		)
		(fp_line
			(start -0.67945 0.3048)
			(end -0.67945 -0.305054)
			(stroke
				(width 0.1)
				(type default)
			)
			(layer "F.Fab")
		)
		(fp_line
			(start -0.67945 -0.305054)
			(end -0.12065 -0.305054)
			(stroke
				(width 0.1)
				(type default)
			)
			(layer "F.Fab")
		)
		(pad "1" smd circle
			(at -0.40005 0 180)
			(size 0 0)
			(layers "F.Cu" "F.Mask" "F.Paste")
			(net "CPU0_PWR_GOOD")
		)
		(pad "2" smd circle
			(at 0.40005 0 180)
			(size 0 0)
			(layers "F.Cu" "F.Mask" "F.Paste")
			(net "FM_CPU0_PWR_GOOD")
		)
	)
	(footprint ""
		(layer "F.Cu")
		(at 401.23364 -378.95403 -90)
		(property "Reference" "C862"
			(at 0 0 270)
			(layer "F.SilkS")
			(hide yes)
			(effects
				(font
					(size 1.27 1.27)
				)
			)
		)
		(property "Value" ""
			(at 0 0 270)
			(layer "F.Fab")
			(effects
				(font
					(size 1.27 1.27)
				)
			)
		)
		(duplicate_pad_numbers_are_jumpers no)
		(fp_line
			(start -0.299974 0.150114)
			(end -0.299974 -0.150114)
			(stroke
				(width 0.1)
				(type default)
			)
			(layer "F.Fab")
		)
		(fp_line
			(start 0.299974 0.150114)
			(end -0.299974 0.150114)
			(stroke
				(width 0.1)
				(type default)
			)
			(layer "F.Fab")
		)
		(fp_line
			(start -0.299974 -0.150114)
			(end 0.299974 -0.150114)
			(stroke
				(width 0.1)
				(type default)
			)
			(layer "F.Fab")
		)
		(fp_line
			(start 0.299974 -0.150114)
			(end 0.299974 0.150114)
			(stroke
				(width 0.1)
				(type default)
			)
			(layer "F.Fab")
		)
		(pad "1" smd rect
			(at -0.2667 0 270)
			(size 0.3048 0.381)
			(layers "F.Cu" "F.Mask" "F.Paste")
			(net "P5E_CPU0_P2_TX_C_DN<3>")
		)
		(pad "2" smd rect
			(at 0.2667 0 270)
			(size 0.3048 0.381)
			(layers "F.Cu" "F.Mask" "F.Paste")
			(net "P5E_CPU0_P2_TX_DN<3>")
		)
	)
	(footprint ""
		(layer "F.Cu")
		(at 365.518446 -28.306522 90)
		(property "Reference" "R825"
			(at 0 0 90)
			(layer "F.SilkS")
			(hide yes)
			(effects
				(font
					(size 1.27 1.27)
				)
			)
		)
		(property "Value" ""
			(at 0 0 90)
			(layer "F.Fab")
			(effects
				(font
					(size 1.27 1.27)
				)
			)
		)
		(duplicate_pad_numbers_are_jumpers no)
		(fp_line
			(start 0.7874 -0.4064)
			(end 0.7874 0.4064)
			(stroke
				(width 0.1524)
				(type default)
			)
			(layer "F.SilkS")
		)
		(fp_line
			(start -0.7874 -0.4064)
			(end 0.7874 -0.4064)
			(stroke
				(width 0.1524)
				(type default)
			)
			(layer "F.SilkS")
		)
		(fp_line
			(start 0.7874 0.4064)
			(end -0.7874 0.4064)
			(stroke
				(width 0.1524)
				(type default)
			)
			(layer "F.SilkS")
		)
		(fp_line
			(start -0.7874 0.4064)
			(end -0.7874 -0.4064)
			(stroke
				(width 0.1524)
				(type default)
			)
			(layer "F.SilkS")
		)
		(fp_line
			(start -0.12065 -0.305054)
			(end -0.12065 -0.2794)
			(stroke
				(width 0.1)
				(type default)
			)
			(layer "F.Fab")
		)
		(fp_line
			(start -0.67945 -0.305054)
			(end -0.12065 -0.305054)
			(stroke
				(width 0.1)
				(type default)
			)
			(layer "F.Fab")
		)
		(fp_line
			(start 0.67945 -0.3048)
			(end 0.67945 0.3048)
			(stroke
				(width 0.1)
				(type default)
			)
			(layer "F.Fab")
		)
		(fp_line
			(start 0.12065 -0.3048)
			(end 0.67945 -0.3048)
			(stroke
				(width 0.1)
				(type default)
			)
			(layer "F.Fab")
		)
		(fp_line
			(start 0.12065 -0.2794)
			(end 0.12065 -0.3048)
			(stroke
				(width 0.1)
				(type default)
			)
			(layer "F.Fab")
		)
		(fp_line
			(start -0.12065 -0.2794)
			(end 0.12065 -0.2794)
			(stroke
				(width 0.1)
				(type default)
			)
			(layer "F.Fab")
		)
		(fp_line
			(start 0.120396 0.2794)
			(end -0.12065 0.2794)
			(stroke
				(width 0.1)
				(type default)
			)
			(layer "F.Fab")
		)
		(fp_line
			(start -0.12065 0.2794)
			(end -0.12065 0.3048)
			(stroke
				(width 0.1)
				(type default)
			)
			(layer "F.Fab")
		)
		(fp_line
			(start 0.67945 0.3048)
			(end 0.120396 0.3048)
			(stroke
				(width 0.1)
				(type default)
			)
			(layer "F.Fab")
		)
		(fp_line
			(start 0.120396 0.3048)
			(end 0.120396 0.2794)
			(stroke
				(width 0.1)
				(type default)
			)
			(layer "F.Fab")
		)
		(fp_line
			(start -0.12065 0.3048)
			(end -0.67945 0.3048)
			(stroke
				(width 0.1)
				(type default)
			)
			(layer "F.Fab")
		)
		(fp_line
			(start -0.67945 0.3048)
			(end -0.67945 -0.305054)
			(stroke
				(width 0.1)
				(type default)
			)
			(layer "F.Fab")
		)
		(pad "1" smd circle
			(at -0.40005 0 90)
			(size 0 0)
			(layers "F.Cu" "F.Mask" "F.Paste")
			(net "P3V3_AUX")
		)
		(pad "2" smd circle
			(at 0.40005 0 90)
			(size 0 0)
			(layers "F.Cu" "F.Mask" "F.Paste")
			(net "UART_CPU0_LVC3_UART0_RX")
		)
	)
)
